(kicad_pcb
	(version 20260206)
	(generator "pcbnew")
	(generator_version "10.0")
	(general
		(thickness 1.6)
		(legacy_teardrops no)
	)
	(paper "A4")
	(title_block
		(title "12092022_DA0F0TFB6D0_F0T_FAN_BOARD_MP5048_D_brd_v02_OCP.brd")
		(comment 1 "Grand Teton / footprints 435-440 of 924")
	)
	(layers
		(0 "F.Cu" signal "TOP")
		(4 "In1.Cu" signal "GND")
		(6 "In2.Cu" signal "IN1")
		(8 "In3.Cu" signal "IN2")
		(10 "In4.Cu" signal "GND1")
		(2 "B.Cu" signal "BOTTOM")
		(9 "F.Adhes" user "F.Adhesive")
		(11 "B.Adhes" user "B.Adhesive")
		(13 "F.Paste" user "Package Geometry/Pastemask Top")
		(15 "B.Paste" user "Package Geometry/Pastemask Bottom")
		(5 "F.SilkS" user "Ref Des/Silkscreen Top")
		(7 "B.SilkS" user "Ref Des/Silkscreen Bottom")
		(1 "F.Mask" user "Board Geometry/Soldermask Top")
		(3 "B.Mask" user "Board Geometry/Soldermask Bottom")
		(17 "Dwgs.User" user "User.Drawings")
		(19 "Cmts.User" user "User.Comments")
		(21 "Eco1.User" user "User.Eco1")
		(23 "Eco2.User" user "User.Eco2")
		(25 "Edge.Cuts" user "Board Geometry/Outline")
		(27 "Margin" user)
		(31 "F.CrtYd" user "Package Geometry/Place Bound Top")
		(29 "B.CrtYd" user "Package Geometry/Place Bound Bottom")
		(35 "F.Fab" user "Ref Des/Assembly Top")
		(33 "B.Fab" user "Ref Des/Assembly Bottom")
	)
	(footprint ""
		(layer "F.Cu")
		(at 34.417 -121.92 90)
		(property "Reference" "R4935"
			(at 0 0 90)
			(layer "F.SilkS")
			(hide yes)
			(effects
				(font
					(size 1.27 1.27)
				)
			)
		)
		(property "Value" ""
			(at 0 0 90)
			(layer "F.Fab")
			(effects
				(font
					(size 1.27 1.27)
				)
			)
		)
		(duplicate_pad_numbers_are_jumpers no)
		(fp_line
			(start 0.7874 -0.4064)
			(end 0.7874 0.4064)
			(stroke
				(width 0.1524)
				(type default)
			)
			(layer "F.SilkS")
		)
		(fp_line
			(start -0.7874 -0.4064)
			(end 0.7874 -0.4064)
			(stroke
				(width 0.1524)
				(type default)
			)
			(layer "F.SilkS")
		)
		(fp_line
			(start 0.7874 0.4064)
			(end -0.7874 0.4064)
			(stroke
				(width 0.1524)
				(type default)
			)
			(layer "F.SilkS")
		)
		(fp_line
			(start -0.7874 0.4064)
			(end -0.7874 -0.4064)
			(stroke
				(width 0.1524)
				(type default)
			)
			(layer "F.SilkS")
		)
		(fp_line
			(start -0.12065 -0.305054)
			(end -0.12065 -0.2794)
			(stroke
				(width 0.1)
				(type default)
			)
			(layer "F.Fab")
		)
		(fp_line
			(start -0.67945 -0.305054)
			(end -0.12065 -0.305054)
			(stroke
				(width 0.1)
				(type default)
			)
			(layer "F.Fab")
		)
		(fp_line
			(start 0.67945 -0.3048)
			(end 0.67945 0.3048)
			(stroke
				(width 0.1)
				(type default)
			)
			(layer "F.Fab")
		)
		(fp_line
			(start 0.12065 -0.3048)
			(end 0.67945 -0.3048)
			(stroke
				(width 0.1)
				(type default)
			)
			(layer "F.Fab")
		)
		(fp_line
			(start 0.12065 -0.2794)
			(end 0.12065 -0.3048)
			(stroke
				(width 0.1)
				(type default)
			)
			(layer "F.Fab")
		)
		(fp_line
			(start -0.12065 -0.2794)
			(end 0.12065 -0.2794)
			(stroke
				(width 0.1)
				(type default)
			)
			(layer "F.Fab")
		)
		(fp_line
			(start 0.120396 0.2794)
			(end -0.12065 0.2794)
			(stroke
				(width 0.1)
				(type default)
			)
			(layer "F.Fab")
		)
		(fp_line
			(start -0.12065 0.2794)
			(end -0.12065 0.3048)
			(stroke
				(width 0.1)
				(type default)
			)
			(layer "F.Fab")
		)
		(fp_line
			(start 0.67945 0.3048)
			(end 0.120396 0.3048)
			(stroke
				(width 0.1)
				(type default)
			)
			(layer "F.Fab")
		)
		(fp_line
			(start 0.120396 0.3048)
			(end 0.120396 0.2794)
			(stroke
				(width 0.1)
				(type default)
			)
			(layer "F.Fab")
		)
		(fp_line
			(start -0.12065 0.3048)
			(end -0.67945 0.3048)
			(stroke
				(width 0.1)
				(type default)
			)
			(layer "F.Fab")
		)
		(fp_line
			(start -0.67945 0.3048)
			(end -0.67945 -0.305054)
			(stroke
				(width 0.1)
				(type default)
			)
			(layer "F.Fab")
		)
		(pad "1" smd circle
			(at -0.40005 0 90)
			(size 0 0)
			(layers "F.Cu" "F.Mask" "F.Paste")
			(net "GND")
		)
		(pad "2" smd circle
			(at 0.40005 0 90)
			(size 0 0)
			(layers "F.Cu" "F.Mask" "F.Paste")
			(net "MAX31790_U317_WD_START")
		)
	)
	(footprint ""
		(layer "F.Cu")
		(at 25.4 -30.734 90)
		(property "Reference" "R5666"
			(at 0 0 90)
			(layer "F.SilkS")
			(hide yes)
			(effects
				(font
					(size 1.27 1.27)
				)
			)
		)
		(property "Value" ""
			(at 0 0 90)
			(layer "F.Fab")
			(effects
				(font
					(size 1.27 1.27)
				)
			)
		)
		(duplicate_pad_numbers_are_jumpers no)
		(fp_line
			(start 0.7874 -0.4064)
			(end 0.7874 0.4064)
			(stroke
				(width 0.1524)
				(type default)
			)
			(layer "F.SilkS")
		)
		(fp_line
			(start -0.7874 -0.4064)
			(end 0.7874 -0.4064)
			(stroke
				(width 0.1524)
				(type default)
			)
			(layer "F.SilkS")
		)
		(fp_line
			(start 0.7874 0.4064)
			(end -0.7874 0.4064)
			(stroke
				(width 0.1524)
				(type default)
			)
			(layer "F.SilkS")
		)
		(fp_line
			(start -0.7874 0.4064)
			(end -0.7874 -0.4064)
			(stroke
				(width 0.1524)
				(type default)
			)
			(layer "F.SilkS")
		)
		(fp_line
			(start -0.12065 -0.305054)
			(end -0.12065 -0.2794)
			(stroke
				(width 0.1)
				(type default)
			)
			(layer "F.Fab")
		)
		(fp_line
			(start -0.67945 -0.305054)
			(end -0.12065 -0.305054)
			(stroke
				(width 0.1)
				(type default)
			)
			(layer "F.Fab")
		)
		(fp_line
			(start 0.67945 -0.3048)
			(end 0.67945 0.3048)
			(stroke
				(width 0.1)
				(type default)
			)
			(layer "F.Fab")
		)
		(fp_line
			(start 0.12065 -0.3048)
			(end 0.67945 -0.3048)
			(stroke
				(width 0.1)
				(type default)
			)
			(layer "F.Fab")
		)
		(fp_line
			(start 0.12065 -0.2794)
			(end 0.12065 -0.3048)
			(stroke
				(width 0.1)
				(type default)
			)
			(layer "F.Fab")
		)
		(fp_line
			(start -0.12065 -0.2794)
			(end 0.12065 -0.2794)
			(stroke
				(width 0.1)
				(type default)
			)
			(layer "F.Fab")
		)
		(fp_line
			(start 0.120396 0.2794)
			(end -0.12065 0.2794)
			(stroke
				(width 0.1)
				(type default)
			)
			(layer "F.Fab")
		)
		(fp_line
			(start -0.12065 0.2794)
			(end -0.12065 0.3048)
			(stroke
				(width 0.1)
				(type default)
			)
			(layer "F.Fab")
		)
		(fp_line
			(start 0.67945 0.3048)
			(end 0.120396 0.3048)
			(stroke
				(width 0.1)
				(type default)
			)
			(layer "F.Fab")
		)
		(fp_line
			(start 0.120396 0.3048)
			(end 0.120396 0.2794)
			(stroke
				(width 0.1)
				(type default)
			)
			(layer "F.Fab")
		)
		(fp_line
			(start -0.12065 0.3048)
			(end -0.67945 0.3048)
			(stroke
				(width 0.1)
				(type default)
			)
			(layer "F.Fab")
		)
		(fp_line
			(start -0.67945 0.3048)
			(end -0.67945 -0.305054)
			(stroke
				(width 0.1)
				(type default)
			)
			(layer "F.Fab")
		)
		(pad "1" smd circle
			(at -0.40005 0 90)
			(size 0 0)
			(layers "F.Cu" "F.Mask" "F.Paste")
			(net "FAN_4_PRESENT")
		)
		(pad "2" smd circle
			(at 0.40005 0 90)
			(size 0 0)
			(layers "F.Cu" "F.Mask" "F.Paste")
			(net "GND")
		)
	)
	(footprint ""
		(layer "F.Cu")
		(at 32.96285 -101.473)
		(property "Reference" "R5329"
			(at 0 0 0)
			(layer "F.SilkS")
			(hide yes)
			(effects
				(font
					(size 1.27 1.27)
				)
			)
		)
		(property "Value" ""
			(at 0 0 0)
			(layer "F.Fab")
			(effects
				(font
					(size 1.27 1.27)
				)
			)
		)
		(duplicate_pad_numbers_are_jumpers no)
		(fp_line
			(start -1.2954 -0.5842)
			(end 1.2954 -0.5842)
			(stroke
				(width 0.1524)
				(type default)
			)
			(layer "F.SilkS")
		)
		(fp_line
			(start -1.2954 0.5842)
			(end -1.2954 -0.5842)
			(stroke
				(width 0.1524)
				(type default)
			)
			(layer "F.SilkS")
		)
		(fp_line
			(start 1.2954 -0.5842)
			(end 1.2954 0.5842)
			(stroke
				(width 0.1524)
				(type default)
			)
			(layer "F.SilkS")
		)
		(fp_line
			(start 1.2954 0.5842)
			(end -1.2954 0.5842)
			(stroke
				(width 0.1524)
				(type default)
			)
			(layer "F.SilkS")
		)
		(fp_line
			(start -1.1938 -0.406654)
			(end -0.8636 -0.406654)
			(stroke
				(width 0.1)
				(type default)
			)
			(layer "F.Fab")
		)
		(fp_line
			(start -1.1938 0.4064)
			(end -1.1938 -0.406654)
			(stroke
				(width 0.1)
				(type default)
			)
			(layer "F.Fab")
		)
		(fp_line
			(start -0.8636 -0.4572)
			(end 0.8636 -0.4572)
			(stroke
				(width 0.1)
				(type default)
			)
			(layer "F.Fab")
		)
		(fp_line
			(start -0.8636 -0.406654)
			(end -0.8636 -0.4572)
			(stroke
				(width 0.1)
				(type default)
			)
			(layer "F.Fab")
		)
		(fp_line
			(start -0.8636 0.4064)
			(end -1.1938 0.4064)
			(stroke
				(width 0.1)
				(type default)
			)
			(layer "F.Fab")
		)
		(fp_line
			(start -0.8636 0.4318)
			(end -0.8636 0.4064)
			(stroke
				(width 0.1)
				(type default)
			)
			(layer "F.Fab")
		)
		(fp_line
			(start -0.8636 0.4572)
			(end -0.8636 0.4318)
			(stroke
				(width 0.1)
				(type default)
			)
			(layer "F.Fab")
		)
		(fp_line
			(start 0.8636 -0.4572)
			(end 0.8636 -0.406654)
			(stroke
				(width 0.1)
				(type default)
			)
			(layer "F.Fab")
		)
		(fp_line
			(start 0.8636 -0.406654)
			(end 1.1938 -0.406654)
			(stroke
				(width 0.1)
				(type default)
			)
			(layer "F.Fab")
		)
		(fp_line
			(start 0.8636 0.4064)
			(end 0.8636 0.4572)
			(stroke
				(width 0.1)
				(type default)
			)
			(layer "F.Fab")
		)
		(fp_line
			(start 0.8636 0.4572)
			(end -0.8636 0.4572)
			(stroke
				(width 0.1)
				(type default)
			)
			(layer "F.Fab")
		)
		(fp_line
			(start 1.1938 -0.406654)
			(end 1.1938 0.4064)
			(stroke
				(width 0.1)
				(type default)
			)
			(layer "F.Fab")
		)
		(fp_line
			(start 1.1938 0.4064)
			(end 0.8636 0.4064)
			(stroke
				(width 0.1)
				(type default)
			)
			(layer "F.Fab")
		)
		(pad "1" smd rect
			(at -0.7366 0 270)
			(size 0.7112 0.8128)
			(layers "F.Cu" "F.Mask" "F.Paste")
			(net "P52V_FAN_2")
		)
		(pad "2" smd rect
			(at 0.7366 0 270)
			(size 0.7112 0.8128)
			(layers "F.Cu" "F.Mask" "F.Paste")
			(net "FAN_2_TACH_OL_R")
		)
	)
	(footprint ""
		(layer "F.Cu")
		(at 14.478 -24.765 180)
		(property "Reference" "D239"
			(at 4.191 -1.04267 0)
			(unlocked yes)
			(layer "F.SilkS")
			(effects
				(font
					(size 0.7874 0.5842)
					(thickness 0.1524)
				)
				(justify left)
			)
		)
		(property "Value" ""
			(at 0 0 180)
			(layer "F.Fab")
			(effects
				(font
					(size 1.27 1.27)
				)
			)
		)
		(duplicate_pad_numbers_are_jumpers no)
		(fp_line
			(start 0.94488 0.450088)
			(end 0.94488 -0.450088)
			(stroke
				(width 0.1524)
				(type default)
			)
			(layer "F.SilkS")
		)
		(fp_line
			(start 0.94488 -0.450088)
			(end -0.854964 -0.450088)
			(stroke
				(width 0.1524)
				(type default)
			)
			(layer "F.SilkS")
		)
		(fp_line
			(start 0.870458 -0.2794)
			(end 0.845058 0.4064)
			(stroke
				(width 0.1524)
				(type default)
			)
			(layer "F.SilkS")
		)
		(fp_line
			(start 0.845058 0.4064)
			(end 0.845058 -0.381)
			(stroke
				(width 0.1524)
				(type default)
			)
			(layer "F.SilkS")
		)
		(fp_line
			(start -0.854964 0.450088)
			(end 0.925068 0.450088)
			(stroke
				(width 0.1524)
				(type default)
			)
			(layer "F.SilkS")
		)
		(fp_line
			(start -0.854964 -0.450088)
			(end -0.854964 0.450088)
			(stroke
				(width 0.1524)
				(type default)
			)
			(layer "F.SilkS")
		)
		(fp_line
			(start 0.54991 0.350012)
			(end 0.54991 -0.350012)
			(stroke
				(width 0.1)
				(type default)
			)
			(layer "F.Fab")
		)
		(fp_line
			(start 0.54991 -0.350012)
			(end -0.54991 -0.350012)
			(stroke
				(width 0.1)
				(type default)
			)
			(layer "F.Fab")
		)
		(fp_line
			(start -0.54991 0.350012)
			(end 0.54991 0.350012)
			(stroke
				(width 0.1)
				(type default)
			)
			(layer "F.Fab")
		)
		(fp_line
			(start -0.54991 -0.350012)
			(end -0.54991 0.350012)
			(stroke
				(width 0.1)
				(type default)
			)
			(layer "F.Fab")
		)
		(fp_text user "-"
			(at 1.905 0.98425 0)
			(unlocked yes)
			(layer "F.SilkS")
			(effects
				(font
					(size 1.905 1.4224)
					(thickness 0.1524)
				)
				(justify left)
			)
		)
		(fp_text user "+"
			(at -0.381 0.98425 0)
			(unlocked yes)
			(layer "F.SilkS")
			(effects
				(font
					(size 1.905 1.4224)
					(thickness 0.1524)
				)
				(justify left)
			)
		)
		(fp_text user "-"
			(at 2.48539 0.239014 0)
			(unlocked yes)
			(layer "F.Fab")
			(effects
				(font
					(size 1.905 1.4224)
					(thickness 0.1524)
				)
				(justify left)
			)
		)
		(fp_text user "+"
			(at -0.808228 0.239014 0)
			(unlocked yes)
			(layer "F.Fab")
			(effects
				(font
					(size 1.905 1.4224)
					(thickness 0.1524)
				)
				(justify left)
			)
		)
		(pad "A" smd rect
			(at -0.424942 0 180)
			(size 0.5588 0.6096)
			(layers "F.Cu" "F.Mask" "F.Paste")
			(net "GND")
		)
		(pad "C" smd rect
			(at 0.424942 0)
			(size 0.5588 0.6096)
			(layers "F.Cu" "F.Mask" "F.Paste")
			(net "FAN_4_FAIL_R_LED_N")
		)
	)
	(footprint ""
		(layer "F.Cu")
		(at 32.258 -291.338 90)
		(property "Reference" "R5384"
			(at 0 0 90)
			(layer "F.SilkS")
			(hide yes)
			(effects
				(font
					(size 1.27 1.27)
				)
			)
		)
		(property "Value" ""
			(at 0 0 90)
			(layer "F.Fab")
			(effects
				(font
					(size 1.27 1.27)
				)
			)
		)
		(duplicate_pad_numbers_are_jumpers no)
		(fp_line
			(start 0.7874 -0.4064)
			(end 0.7874 0.4064)
			(stroke
				(width 0.1524)
				(type default)
			)
			(layer "F.SilkS")
		)
		(fp_line
			(start -0.7874 -0.4064)
			(end 0.7874 -0.4064)
			(stroke
				(width 0.1524)
				(type default)
			)
			(layer "F.SilkS")
		)
		(fp_line
			(start 0.7874 0.4064)
			(end -0.7874 0.4064)
			(stroke
				(width 0.1524)
				(type default)
			)
			(layer "F.SilkS")
		)
		(fp_line
			(start -0.7874 0.4064)
			(end -0.7874 -0.4064)
			(stroke
				(width 0.1524)
				(type default)
			)
			(layer "F.SilkS")
		)
		(fp_line
			(start -0.12065 -0.305054)
			(end -0.12065 -0.2794)
			(stroke
				(width 0.1)
				(type default)
			)
			(layer "F.Fab")
		)
		(fp_line
			(start -0.67945 -0.305054)
			(end -0.12065 -0.305054)
			(stroke
				(width 0.1)
				(type default)
			)
			(layer "F.Fab")
		)
		(fp_line
			(start 0.67945 -0.3048)
			(end 0.67945 0.3048)
			(stroke
				(width 0.1)
				(type default)
			)
			(layer "F.Fab")
		)
		(fp_line
			(start 0.12065 -0.3048)
			(end 0.67945 -0.3048)
			(stroke
				(width 0.1)
				(type default)
			)
			(layer "F.Fab")
		)
		(fp_line
			(start 0.12065 -0.2794)
			(end 0.12065 -0.3048)
			(stroke
				(width 0.1)
				(type default)
			)
			(layer "F.Fab")
		)
		(fp_line
			(start -0.12065 -0.2794)
			(end 0.12065 -0.2794)
			(stroke
				(width 0.1)
				(type default)
			)
			(layer "F.Fab")
		)
		(fp_line
			(start 0.120396 0.2794)
			(end -0.12065 0.2794)
			(stroke
				(width 0.1)
				(type default)
			)
			(layer "F.Fab")
		)
		(fp_line
			(start -0.12065 0.2794)
			(end -0.12065 0.3048)
			(stroke
				(width 0.1)
				(type default)
			)
			(layer "F.Fab")
		)
		(fp_line
			(start 0.67945 0.3048)
			(end 0.120396 0.3048)
			(stroke
				(width 0.1)
				(type default)
			)
			(layer "F.Fab")
		)
		(fp_line
			(start 0.120396 0.3048)
			(end 0.120396 0.2794)
			(stroke
				(width 0.1)
				(type default)
			)
			(layer "F.Fab")
		)
		(fp_line
			(start -0.12065 0.3048)
			(end -0.67945 0.3048)
			(stroke
				(width 0.1)
				(type default)
			)
			(layer "F.Fab")
		)
		(fp_line
			(start -0.67945 0.3048)
			(end -0.67945 -0.305054)
			(stroke
				(width 0.1)
				(type default)
			)
			(layer "F.Fab")
		)
		(pad "1" smd circle
			(at -0.40005 0 90)
			(size 0 0)
			(layers "F.Cu" "F.Mask" "F.Paste")
			(net "P3V3_AUX")
		)
		(pad "2" smd circle
			(at 0.40005 0 90)
			(size 0 0)
			(layers "F.Cu" "F.Mask" "F.Paste")
			(net "FAN_0_OK_R_LED")
		)
	)
	(footprint ""
		(layer "F.Cu")
		(at 31.623 -124.206 90)
		(property "Reference" "R4779"
			(at 0 0 90)
			(layer "F.SilkS")
			(hide yes)
			(effects
				(font
					(size 1.27 1.27)
				)
			)
		)
		(property "Value" ""
			(at 0 0 90)
			(layer "F.Fab")
			(effects
				(font
					(size 1.27 1.27)
				)
			)
		)
		(duplicate_pad_numbers_are_jumpers no)
		(fp_line
			(start 0.7874 -0.4064)
			(end 0.7874 0.4064)
			(stroke
				(width 0.1524)
				(type default)
			)
			(layer "F.SilkS")
		)
		(fp_line
			(start -0.7874 -0.4064)
			(end 0.7874 -0.4064)
			(stroke
				(width 0.1524)
				(type default)
			)
			(layer "F.SilkS")
		)
		(fp_line
			(start 0.7874 0.4064)
			(end -0.7874 0.4064)
			(stroke
				(width 0.1524)
				(type default)
			)
			(layer "F.SilkS")
		)
		(fp_line
			(start -0.7874 0.4064)
			(end -0.7874 -0.4064)
			(stroke
				(width 0.1524)
				(type default)
			)
			(layer "F.SilkS")
		)
		(fp_line
			(start -0.12065 -0.305054)
			(end -0.12065 -0.2794)
			(stroke
				(width 0.1)
				(type default)
			)
			(layer "F.Fab")
		)
		(fp_line
			(start -0.67945 -0.305054)
			(end -0.12065 -0.305054)
			(stroke
				(width 0.1)
				(type default)
			)
			(layer "F.Fab")
		)
		(fp_line
			(start 0.67945 -0.3048)
			(end 0.67945 0.3048)
			(stroke
				(width 0.1)
				(type default)
			)
			(layer "F.Fab")
		)
		(fp_line
			(start 0.12065 -0.3048)
			(end 0.67945 -0.3048)
			(stroke
				(width 0.1)
				(type default)
			)
			(layer "F.Fab")
		)
		(fp_line
			(start 0.12065 -0.2794)
			(end 0.12065 -0.3048)
			(stroke
				(width 0.1)
				(type default)
			)
			(layer "F.Fab")
		)
		(fp_line
			(start -0.12065 -0.2794)
			(end 0.12065 -0.2794)
			(stroke
				(width 0.1)
				(type default)
			)
			(layer "F.Fab")
		)
		(fp_line
			(start 0.120396 0.2794)
			(end -0.12065 0.2794)
			(stroke
				(width 0.1)
				(type default)
			)
			(layer "F.Fab")
		)
		(fp_line
			(start -0.12065 0.2794)
			(end -0.12065 0.3048)
			(stroke
				(width 0.1)
				(type default)
			)
			(layer "F.Fab")
		)
		(fp_line
			(start 0.67945 0.3048)
			(end 0.120396 0.3048)
			(stroke
				(width 0.1)
				(type default)
			)
			(layer "F.Fab")
		)
		(fp_line
			(start 0.120396 0.3048)
			(end 0.120396 0.2794)
			(stroke
				(width 0.1)
				(type default)
			)
			(layer "F.Fab")
		)
		(fp_line
			(start -0.12065 0.3048)
			(end -0.67945 0.3048)
			(stroke
				(width 0.1)
				(type default)
			)
			(layer "F.Fab")
		)
		(fp_line
			(start -0.67945 0.3048)
			(end -0.67945 -0.305054)
			(stroke
				(width 0.1)
				(type default)
			)
			(layer "F.Fab")
		)
		(pad "1" smd circle
			(at -0.40005 0 90)
			(size 0 0)
			(layers "F.Cu" "F.Mask" "F.Paste")
			(net "P3V3_AUX")
		)
		(pad "2" smd circle
			(at 0.40005 0 90)
			(size 0 0)
			(layers "F.Cu" "F.Mask" "F.Paste")
			(net "MAX31790_U317_ADD1")
		)
	)
)
